(kicad_pcb
	(version 20241229)
	(generator "pcbnew")
	(generator_version "9.0")
	(general
		(thickness 1.63)
		(legacy_teardrops no)
	)
	(paper "A4")
	(title_block
		(title "CM4 Baseboard")
		(date "2026-01-05")
		(rev "1.1.1")
		(company "Antmicro Ltd")
		(comment 1 "www.antmicro.com")
		(comment 9 "footprints 445-448 of 506")
	)
	(layers
		(0 "F.Cu" signal)
		(4 "In1.Cu" power)
		(6 "In2.Cu" power)
		(8 "In3.Cu" signal)
		(10 "In4.Cu" signal)
		(2 "B.Cu" signal)
		(9 "F.Adhes" user "F.Adhesive")
		(11 "B.Adhes" user "B.Adhesive")
		(13 "F.Paste" user)
		(15 "B.Paste" user)
		(5 "F.SilkS" user "F.Silkscreen")
		(7 "B.SilkS" user "B.Silkscreen")
		(1 "F.Mask" user)
		(3 "B.Mask" user)
		(17 "Dwgs.User" user "User.Drawings")
		(19 "Cmts.User" user "User.Comments")
		(21 "Eco1.User" user "User.Eco1")
		(23 "Eco2.User" user "User.Eco2")
		(25 "Edge.Cuts" user)
		(27 "Margin" user)
		(31 "F.CrtYd" user "F.Courtyard")
		(29 "B.CrtYd" user "B.Courtyard")
		(35 "F.Fab" user)
		(33 "B.Fab" user)
	)
	(footprint "antmicro-footprints:SOT-523"
		(layer "B.Cu")
		(at 74.8 152.9 -90)
		(property "Reference" "Q214"
			(at 2 -1.05 180)
			(layer "B.SilkS")
			(effects
				(font
					(size 0.7 0.7)
					(thickness 0.15)
				)
				(justify left bottom mirror)
			)
		)
		(property "Value" "PJE138K"
			(at 0.1 -1.824 90)
			(layer "B.Fab")
			(effects
				(font
					(size 0.7 0.7)
					(thickness 0.15)
				)
				(justify left bottom mirror)
			)
		)
		(property "Datasheet" "https://www.mouser.com/datasheet/2/1057/PJE138K-1876698.pdf"
			(at 0 0 270)
			(layer "B.Fab")
			(hide yes)
			(effects
				(font
					(size 1.27 1.27)
					(thickness 0.15)
				)
			)
		)
		(property "MPN" "PJE138K_R1_00001"
			(at 0 0 270)
			(unlocked yes)
			(layer "B.Fab")
			(hide yes)
			(effects
				(font
					(size 1 1)
					(thickness 0.15)
				)
				(justify mirror)
			)
		)
		(property "Manufacturer" "PANJIT"
			(at 0 0 270)
			(unlocked yes)
			(layer "B.Fab")
			(hide yes)
			(effects
				(font
					(size 1 1)
					(thickness 0.15)
				)
				(justify mirror)
			)
		)
		(property "Author" "Antmicro"
			(at 0 0 270)
			(unlocked yes)
			(layer "B.Fab")
			(hide yes)
			(effects
				(font
					(size 1 1)
					(thickness 0.15)
				)
				(justify mirror)
			)
		)
		(property "License" "Apache-2.0"
			(at 0 0 270)
			(unlocked yes)
			(layer "B.Fab")
			(hide yes)
			(effects
				(font
					(size 1 1)
					(thickness 0.15)
				)
				(justify mirror)
			)
		)
		(sheetname "/Compute module/")
		(sheetfile "compute-module.kicad_sch")
		(attr smd)
		(fp_line
			(start -0.725 0.551)
			(end -0.277 0.551)
			(stroke
				(width 0.15)
				(type solid)
			)
			(layer "B.SilkS")
		)
		(fp_line
			(start -0.277 0.551)
			(end -0.277 0.75)
			(stroke
				(width 0.15)
				(type solid)
			)
			(layer "B.SilkS")
		)
		(fp_line
			(start -0.927 0.351)
			(end -0.725 0.551)
			(stroke
				(width 0.15)
				(type solid)
			)
			(layer "B.SilkS")
		)
		(fp_line
			(start -0.927 0.051)
			(end -0.927 0.351)
			(stroke
				(width 0.15)
				(type solid)
			)
			(layer "B.SilkS")
		)
		(fp_circle
			(center -0.9652 -0.9652)
			(end -0.9152 -0.9652)
			(stroke
				(width 0.15)
				(type solid)
			)
			(fill yes)
			(layer "B.SilkS")
		)
		(fp_line
			(start -1.12 1.16)
			(end 1.1 1.16)
			(stroke
				(width 0.05)
				(type solid)
			)
			(layer "B.CrtYd")
		)
		(fp_line
			(start -1.12 1.16)
			(end -1.12 -1.15)
			(stroke
				(width 0.05)
				(type solid)
			)
			(layer "B.CrtYd")
		)
		(fp_line
			(start 1.1 1.16)
			(end 1.1 -1.15)
			(stroke
				(width 0.05)
				(type solid)
			)
			(layer "B.CrtYd")
		)
		(fp_line
			(start -1.12 -1.15)
			(end 1.1 -1.15)
			(stroke
				(width 0.05)
				(type solid)
			)
			(layer "B.CrtYd")
		)
		(fp_line
			(start -0.652 0.425)
			(end -0.802 0.276)
			(stroke
				(width 0.15)
				(type solid)
			)
			(layer "B.Fab")
		)
		(fp_line
			(start 0.8 0.425)
			(end -0.652 0.425)
			(stroke
				(width 0.15)
				(type solid)
			)
			(layer "B.Fab")
		)
		(fp_line
			(start 0.8 0.425)
			(end 0.8 -0.424)
			(stroke
				(width 0.15)
				(type solid)
			)
			(layer "B.Fab")
		)
		(fp_line
			(start -0.802 0.276)
			(end -0.802 -0.424)
			(stroke
				(width 0.15)
				(type solid)
			)
			(layer "B.Fab")
		)
		(fp_line
			(start 0.8 -0.424)
			(end -0.802 -0.424)
			(stroke
				(width 0.15)
				(type solid)
			)
			(layer "B.Fab")
		)
		(fp_circle
			(center -0.9652 -0.9652)
			(end -0.9144 -0.9652)
			(stroke
				(width 0.15)
				(type solid)
			)
			(fill no)
			(layer "B.Fab")
		)
		(fp_text user "Author: Antmicro"
			(at -1.12 -6.224 90)
			(layer "B.Fab")
			(effects
				(font
					(size 0.7 0.7)
					(thickness 0.15)
				)
				(justify left bottom mirror)
			)
		)
		(fp_text user "${REFERENCE}"
			(at -1.12 -3.824 90)
			(layer "B.Fab")
			(effects
				(font
					(size 0.7 0.7)
					(thickness 0.15)
				)
				(justify left bottom mirror)
			)
		)
		(fp_text user "License: Apache-2.0"
			(at -1.12 -5.024 90)
			(layer "B.Fab")
			(effects
				(font
					(size 0.7 0.7)
					(thickness 0.15)
				)
				(justify left bottom mirror)
			)
		)
		(pad "1" smd rect
			(at -0.5 -0.65 270)
			(size 0.4 0.51)
			(layers "B.Cu" "B.Mask" "B.Paste")
			(net 18 "V_{IO}")
			(pinfunction "G")
			(pintype "input")
		)
		(pad "2" smd rect
			(at 0.498 -0.65 270)
			(size 0.4 0.51)
			(layers "B.Cu" "B.Mask" "B.Paste")
			(net 3 "GND")
			(pinfunction "S")
			(pintype "passive")
		)
		(pad "3" smd rect
			(at 0 0.652 270)
			(size 0.4 0.51)
			(layers "B.Cu" "B.Mask" "B.Paste")
			(net 500 "Net-(Q214-D)")
			(pinfunction "D")
			(pintype "passive")
		)
	)
	(footprint "antmicro-footprints:L_Coilcraft-XAL6030"
		(layer "B.Cu")
		(at 61.242962 157.1915 -90)
		(property "Reference" "L303"
			(at -3.745 -4.465 90)
			(unlocked yes)
			(layer "B.SilkS")
			(effects
				(font
					(size 0.7 0.7)
					(thickness 0.15)
				)
				(justify left bottom mirror)
			)
		)
		(property "Value" "L_1u8_14A_Coilcraft-XAL6030"
			(at 0 -4.7 90)
			(unlocked yes)
			(layer "B.Fab")
			(effects
				(font
					(size 0.7 0.7)
					(thickness 0.15)
				)
				(justify left bottom mirror)
			)
		)
		(property "Datasheet" "https://www.mouser.com/datasheet/2/597/xal60xx-270658.pdf"
			(at 0 0 270)
			(layer "B.Fab")
			(hide yes)
			(effects
				(font
					(size 1.27 1.27)
					(thickness 0.15)
				)
			)
		)
		(property "Manufacturer" "Coilcraft"
			(at 0 0 270)
			(unlocked yes)
			(layer "B.Fab")
			(hide yes)
			(effects
				(font
					(size 1 1)
					(thickness 0.15)
				)
				(justify mirror)
			)
		)
		(property "MPN" "XAL6030-182MEC"
			(at 0 0 270)
			(unlocked yes)
			(layer "B.Fab")
			(hide yes)
			(effects
				(font
					(size 1 1)
					(thickness 0.15)
				)
				(justify mirror)
			)
		)
		(property "Size" "6.36x6.56"
			(at 0 0 270)
			(unlocked yes)
			(layer "B.Fab")
			(hide yes)
			(effects
				(font
					(size 1 1)
					(thickness 0.15)
				)
				(justify mirror)
			)
		)
		(property "Val" "1.8u/14A"
			(at 0 0 270)
			(unlocked yes)
			(layer "B.Fab")
			(hide yes)
			(effects
				(font
					(size 1 1)
					(thickness 0.15)
				)
				(justify mirror)
			)
		)
		(property "Author" "Antmicro"
			(at 0 0 270)
			(unlocked yes)
			(layer "B.Fab")
			(hide yes)
			(effects
				(font
					(size 1 1)
					(thickness 0.15)
				)
				(justify mirror)
			)
		)
		(property "License" "Apache-2.0"
			(at 0 0 270)
			(unlocked yes)
			(layer "B.Fab")
			(hide yes)
			(effects
				(font
					(size 1 1)
					(thickness 0.15)
				)
				(justify mirror)
			)
		)
		(property "ISat" "18.2 A"
			(at 0 0 270)
			(unlocked yes)
			(layer "B.Fab")
			(hide yes)
			(effects
				(font
					(size 1 1)
					(thickness 0.15)
				)
				(justify mirror)
			)
		)
		(property "IMax" "14 A"
			(at 0 0 270)
			(unlocked yes)
			(layer "B.Fab")
			(hide yes)
			(effects
				(font
					(size 1 1)
					(thickness 0.15)
				)
				(justify mirror)
			)
		)
		(sheetname "/Supply/")
		(sheetfile "supply.kicad_sch")
		(attr smd)
		(fp_rect
			(start -3.299 3.4)
			(end 3.299 -3.4)
			(stroke
				(width 0.15)
				(type solid)
			)
			(fill no)
			(layer "B.SilkS")
		)
		(fp_rect
			(start -3.52 3.63)
			(end 3.52 -3.63)
			(stroke
				(width 0.05)
				(type solid)
			)
			(fill no)
			(layer "B.CrtYd")
		)
		(fp_rect
			(start -3.279 3.38)
			(end 3.279 -3.38)
			(stroke
				(width 0.15)
				(type solid)
			)
			(fill no)
			(layer "B.Fab")
		)
		(fp_text user "Author: Antmicro"
			(at -3.52 -6.7 90)
			(layer "B.Fab")
			(effects
				(font
					(size 0.7 0.7)
					(thickness 0.15)
				)
				(justify left bottom mirror)
			)
		)
		(fp_text user "${REFERENCE}"
			(at -3.52 -7.9 90)
			(unlocked yes)
			(layer "B.Fab")
			(effects
				(font
					(size 0.7 0.7)
					(thickness 0.15)
				)
				(justify left bottom mirror)
			)
		)
		(fp_text user "License: Apache-2.0"
			(at -3.52 -9.1 90)
			(layer "B.Fab")
			(effects
				(font
					(size 0.7 0.7)
					(thickness 0.15)
				)
				(justify left bottom mirror)
			)
		)
		(pad "1" smd roundrect
			(at -2.02 0 270)
			(size 1.43 5.5)
			(layers "B.Cu" "B.Mask" "B.Paste")
			(roundrect_rratio 0.1)
			(net 59 "/Supply/SW_5V")
			(pintype "passive")
		)
		(pad "2" smd roundrect
			(at 2.019 0 270)
			(size 1.43 5.5)
			(layers "B.Cu" "B.Mask" "B.Paste")
			(roundrect_rratio 0.1)
			(net 77 "/Supply/OUT_5V")
			(pintype "passive")
		)
	)
	(footprint "antmicro-footprints:R_0402_1005Metric"
		(layer "B.Cu")
		(at 108.077962 133.0415 -90)
		(descr "Resistor SMD 0402")
		(tags "resistor SMD 0402")
		(property "Reference" "R318"
			(at -3.675 -0.4 90)
			(layer "B.SilkS")
			(effects
				(font
					(size 0.7 0.7)
					(thickness 0.15)
				)
				(justify left bottom mirror)
			)
		)
		(property "Value" "R_6k8_0402"
			(at -1.011843 -1.772047 90)
			(layer "B.Fab")
			(effects
				(font
					(size 0.7 0.7)
					(thickness 0.15)
				)
				(justify left bottom mirror)
			)
		)
		(property "Datasheet" "https://www.bourns.com/docs/product-datasheets/cr.pdf"
			(at 0 0 270)
			(layer "B.Fab")
			(hide yes)
			(effects
				(font
					(size 1.27 1.27)
					(thickness 0.15)
				)
			)
		)
		(property "MPN" "CR0402-FX-6801GLF"
			(at 0 0 270)
			(unlocked yes)
			(layer "B.Fab")
			(hide yes)
			(effects
				(font
					(size 1 1)
					(thickness 0.15)
				)
				(justify mirror)
			)
		)
		(property "Manufacturer" "Bourns"
			(at 0 0 270)
			(unlocked yes)
			(layer "B.Fab")
			(hide yes)
			(effects
				(font
					(size 1 1)
					(thickness 0.15)
				)
				(justify mirror)
			)
		)
		(property "License" "Apache-2.0"
			(at 0 0 270)
			(unlocked yes)
			(layer "B.Fab")
			(hide yes)
			(effects
				(font
					(size 1 1)
					(thickness 0.15)
				)
				(justify mirror)
			)
		)
		(property "Author" "Antmicro"
			(at 0 0 270)
			(unlocked yes)
			(layer "B.Fab")
			(hide yes)
			(effects
				(font
					(size 1 1)
					(thickness 0.15)
				)
				(justify mirror)
			)
		)
		(property "Val" "6k8"
			(at 0 0 270)
			(unlocked yes)
			(layer "B.Fab")
			(hide yes)
			(effects
				(font
					(size 1 1)
					(thickness 0.15)
				)
				(justify mirror)
			)
		)
		(property "Tolerance" "1%"
			(at 0 0 270)
			(unlocked yes)
			(layer "B.Fab")
			(hide yes)
			(effects
				(font
					(size 1 1)
					(thickness 0.15)
				)
				(justify mirror)
			)
		)
		(sheetname "/Supply/")
		(sheetfile "supply.kicad_sch")
		(attr smd)
		(fp_rect
			(start -0.925 0.47)
			(end 0.925 -0.47)
			(stroke
				(width 0.05)
				(type default)
			)
			(fill no)
			(layer "B.CrtYd")
		)
		(fp_rect
			(start -0.5 0.25)
			(end 0.5 -0.25)
			(stroke
				(width 0.15)
				(type solid)
			)
			(fill no)
			(layer "B.Fab")
		)
		(fp_text user "Author: Antmicro"
			(at -0.95 -4.169 90)
			(layer "B.Fab")
			(effects
				(font
					(size 0.7 0.7)
					(thickness 0.15)
				)
				(justify left bottom mirror)
			)
		)
		(fp_text user "License: Apache-2.0"
			(at -0.95 -5.169 90)
			(layer "B.Fab")
			(effects
				(font
					(size 0.7 0.7)
					(thickness 0.15)
				)
				(justify left bottom mirror)
			)
		)
		(fp_text user "${REFERENCE}"
			(at -0.95 -3.168 90)
			(layer "B.Fab")
			(effects
				(font
					(size 0.7 0.7)
					(thickness 0.15)
				)
				(justify left bottom mirror)
			)
		)
		(pad "1" smd roundrect
			(at -0.48 0 270)
			(size 0.59 0.64)
			(layers "B.Cu" "B.Mask" "B.Paste")
			(roundrect_rratio 0.25)
			(net 354 "/Supply/FB_M2")
			(pintype "passive")
		)
		(pad "2" smd roundrect
			(at 0.48 0 270)
			(size 0.59 0.64)
			(layers "B.Cu" "B.Mask" "B.Paste")
			(roundrect_rratio 0.25)
			(net 78 "/Supply/OUT_M2")
			(pintype "passive")
		)
	)
	(footprint "antmicro-footprints:Vishay_PowerPAK_1212-8_Single"
		(layer "B.Cu")
		(at 49.766962 163.3075 -90)
		(descr "PowerPAK 1212-8 Single")
		(tags "Vishay PowerPAK 1212-8 Single")
		(property "Reference" "Q306"
			(at -2.041 1.399 0)
			(layer "B.SilkS")
			(effects
				(font
					(size 0.7 0.7)
					(thickness 0.15)
				)
				(justify right bottom mirror)
			)
		)
		(property "Value" "SQS401EN-T1_BE3"
			(at 0 -2.7 90)
			(layer "B.Fab")
			(effects
				(font
					(size 0.7 0.7)
					(thickness 0.15)
				)
				(justify left bottom mirror)
			)
		)
		(property "Datasheet" "https://www.vishay.com/docs/65529/sqs401en.pdf"
			(at 0 0 270)
			(layer "B.Fab")
			(hide yes)
			(effects
				(font
					(size 1.27 1.27)
					(thickness 0.15)
				)
			)
		)
		(property "MPN" "SQS401EN-T1_BE3"
			(at 0 0 270)
			(unlocked yes)
			(layer "B.Fab")
			(hide yes)
			(effects
				(font
					(size 1 1)
					(thickness 0.15)
				)
				(justify mirror)
			)
		)
		(property "Manufacturer" "Vishay"
			(at 0 0 270)
			(unlocked yes)
			(layer "B.Fab")
			(hide yes)
			(effects
				(font
					(size 1 1)
					(thickness 0.15)
				)
				(justify mirror)
			)
		)
		(property "Author" "Antmicro"
			(at 0 0 270)
			(unlocked yes)
			(layer "B.Fab")
			(hide yes)
			(effects
				(font
					(size 1 1)
					(thickness 0.15)
				)
				(justify mirror)
			)
		)
		(property "License" "Apache-2.0"
			(at 0 0 270)
			(unlocked yes)
			(layer "B.Fab")
			(hide yes)
			(effects
				(font
					(size 1 1)
					(thickness 0.15)
				)
				(justify mirror)
			)
		)
		(sheetname "/Supply/")
		(sheetfile "supply.kicad_sch")
		(attr smd)
		(fp_line
			(start -1.651 1.651)
			(end 1.648 1.651)
			(stroke
				(width 0.15)
				(type solid)
			)
			(layer "B.SilkS")
		)
		(fp_line
			(start -1.651 1.651)
			(end -1.651 1.317)
			(stroke
				(width 0.15)
				(type solid)
			)
			(layer "B.SilkS")
		)
		(fp_line
			(start 1.648 1.651)
			(end 1.648 1.317)
			(stroke
				(width 0.15)
				(type solid)
			)
			(layer "B.SilkS")
		)
		(fp_line
			(start -1.635 -1.3)
			(end -1.635 -1.634)
			(stroke
				(width 0.15)
				(type solid)
			)
			(layer "B.SilkS")
		)
		(fp_line
			(start 1.634 -1.3)
			(end 1.634 -1.634)
			(stroke
				(width 0.15)
				(type solid)
			)
			(layer "B.SilkS")
		)
		(fp_line
			(start -1.635 -1.634)
			(end 1.634 -1.634)
			(stroke
				(width 0.15)
				(type solid)
			)
			(layer "B.SilkS")
		)
		(fp_circle
			(center -1.9 1.4)
			(end -1.85 1.4)
			(stroke
				(width 0.15)
				(type solid)
			)
			(fill yes)
			(layer "B.SilkS")
		)
		(fp_rect
			(start -2 1.8)
			(end 2 -1.798)
			(stroke
				(width 0.05)
				(type solid)
			)
			(fill no)
			(layer "B.CrtYd")
		)
		(fp_line
			(start -1.6425 1.4175)
			(end -1.4175 1.6425)
			(stroke
				(width 0.15)
				(type solid)
			)
			(layer "B.Fab")
		)
		(fp_rect
			(start -1.651 1.651)
			(end 1.648 -1.648)
			(stroke
				(width 0.15)
				(type solid)
			)
			(fill no)
			(layer "B.Fab")
		)
		(fp_text user "Author: Antmicro"
			(at -8 -5.9 90)
			(layer "B.Fab")
			(effects
				(font
					(size 0.7 0.7)
					(thickness 0.15)
				)
				(justify left bottom mirror)
			)
		)
		(fp_text user "${REFERENCE}"
			(at -8 -4.7 90)
			(layer "B.Fab")
			(effects
				(font
					(size 0.7 0.7)
					(thickness 0.15)
				)
				(justify left bottom mirror)
			)
		)
		(fp_text user "License: Apache-2.0"
			(at -8 -7.1 90)
			(layer "B.Fab")
			(effects
				(font
					(size 0.7 0.7)
					(thickness 0.15)
				)
				(justify left bottom mirror)
			)
		)
		(pad "1" smd rect
			(at -1.436 0.99 270)
			(size 0.99 0.405)
			(layers "B.Cu" "B.Mask" "B.Paste")
			(net 21 "/Supply/VCC_IN")
			(pinfunction "S")
			(pintype "passive")
		)
		(pad "2" smd rect
			(at -1.436 0.332 270)
			(size 0.99 0.405)
			(layers "B.Cu" "B.Mask" "B.Paste")
			(net 21 "/Supply/VCC_IN")
			(pinfunction "S")
			(pintype "passive")
		)
		(pad "3" smd rect
			(at -1.436 -0.33 270)
			(size 0.99 0.405)
			(layers "B.Cu" "B.Mask" "B.Paste")
			(net 21 "/Supply/VCC_IN")
			(pinfunction "S")
			(pintype "passive")
		)
		(pad "4" smd rect
			(at -1.436 -0.988 270)
			(size 0.99 0.405)
			(layers "B.Cu" "B.Mask" "B.Paste")
			(net 337 "Net-(Q303-BIAS)")
			(pinfunction "G")
			(pintype "input")
		)
		(pad "5" smd custom
			(at 0.557 0 270)
			(size 1.725 2.235)
			(layers "B.Cu" "B.Mask" "B.Paste")
			(net 443 "/Supply/V_{BUS}")
			(pinfunction "D")
			(pintype "passive")
			(zone_connect 2)
			(options
				(clearance outline)
				(anchor rect)
			)
			(primitives
				(gr_poly
					(pts
						(xy 0.8625 -0.1275) (xy 0.8625 0.1275) (xy 1.3725 0.1275) (xy 1.3725 0.5325) (xy 0.8625 0.5325)
						(xy 0.8625 0.7875) (xy 1.3725 0.7875) (xy 1.3725 1.195) (xy 0.6125 1.195) (xy 0.6125 -1.195) (xy 1.3725 -1.195)
						(xy 1.3725 -0.7875) (xy 0.8625 -0.7875) (xy 0.8625 -0.5325) (xy 1.3725 -0.5325) (xy 1.3725 -0.1275)
					)
					(width 0)
					(fill yes)
				)
			)
		)
	)
)
